(kicad_pcb
	(version 20241229)
	(generator "pcbnew")
	(generator_version "9.0")
	(general
		(thickness 1.62)
		(legacy_teardrops no)
	)
	(paper "A3")
	(title_block
		(title "COM Express 7 Baseboard")
		(date "2025-02-04")
		(rev "1.1.2")
		(company "Antmicro Ltd")
		(comment 1 "www.antmicro.com")
		(comment 9 "footprints 426-428 of 802")
	)
	(layers
		(0 "F.Cu" signal)
		(4 "In1.Cu" signal)
		(6 "In2.Cu" signal)
		(8 "In3.Cu" signal)
		(10 "In4.Cu" signal)
		(12 "In5.Cu" signal)
		(14 "In6.Cu" signal)
		(2 "B.Cu" signal)
		(9 "F.Adhes" user "F.Adhesive")
		(11 "B.Adhes" user "B.Adhesive")
		(13 "F.Paste" user)
		(15 "B.Paste" user)
		(5 "F.SilkS" user "F.Silkscreen")
		(7 "B.SilkS" user "B.Silkscreen")
		(1 "F.Mask" user)
		(3 "B.Mask" user)
		(17 "Dwgs.User" user "User.Drawings")
		(19 "Cmts.User" user "User.Comments")
		(21 "Eco1.User" user "User.Eco1")
		(23 "Eco2.User" user "User.Eco2")
		(25 "Edge.Cuts" user)
		(27 "Margin" user)
		(31 "F.CrtYd" user "F.Courtyard")
		(29 "B.CrtYd" user "B.Courtyard")
		(35 "F.Fab" user)
		(33 "B.Fab" user)
	)
	(footprint "antmicro-footprints:Spacer_Drill3.7mm_H5mm_9774050151R"
		(layer "F.Cu")
		(at 161.93 80.8 90)
		(descr "Spacer M=3 h=5mm fi=5.1mm")
		(property "Reference" "H7"
			(at 0 -3.2 90)
			(layer "F.SilkS")
			(hide yes)
			(effects
				(font
					(size 0.7 0.7)
					(thickness 0.15)
				)
				(justify left bottom)
			)
		)
		(property "Value" "Spacer_Drill3.7mm_H5mm_9774050151R"
			(at 0 4 90)
			(layer "F.Fab")
			(effects
				(font
					(size 0.7 0.7)
					(thickness 0.15)
				)
				(justify left bottom)
			)
		)
		(property "Datasheet" "https://www.we-online.com/catalog/datasheet/9774050151.pdf"
			(at 0 0 90)
			(layer "F.Fab")
			(hide yes)
			(effects
				(font
					(size 1.27 1.27)
					(thickness 0.15)
				)
			)
		)
		(property "Author" "Antmicro"
			(at 242.74 -81.12 0)
			(layer "F.Fab")
			(hide yes)
			(effects
				(font
					(size 1 1)
					(thickness 0.15)
				)
			)
		)
		(property "License" "Apache-2.0"
			(at 242.74 -81.12 0)
			(layer "F.Fab")
			(hide yes)
			(effects
				(font
					(size 1 1)
					(thickness 0.15)
				)
			)
		)
		(property "MPN" "9774050151R"
			(at 242.74 -81.12 0)
			(layer "F.Fab")
			(hide yes)
			(effects
				(font
					(size 1 1)
					(thickness 0.15)
				)
			)
		)
		(property "Manufacturer" "Würth Elektronik"
			(at 242.74 -81.12 0)
			(layer "F.Fab")
			(hide yes)
			(effects
				(font
					(size 1 1)
					(thickness 0.15)
				)
			)
		)
		(sheetname "Com Express 7 Interfaces")
		(sheetfile "com_express_7_interfaces.kicad_sch")
		(solder_paste_margin_ratio -1)
		(attr smd)
		(fp_circle
			(center 0 0)
			(end 3.05 0)
			(stroke
				(width 0.05)
				(type solid)
			)
			(fill no)
			(layer "F.CrtYd")
		)
		(fp_circle
			(center 0 0)
			(end 2.6 0)
			(stroke
				(width 0.15)
				(type solid)
			)
			(fill no)
			(layer "F.Fab")
		)
		(pad "" smd custom
			(at -1.7 -1.7 90)
			(size 0.62 0.62)
			(layers "F.Paste")
			(thermal_bridge_angle 90)
			(options
				(clearance outline)
				(anchor circle)
			)
			(primitives
				(gr_arc
					(start -0.250195 1.279127)
					(mid 0.285453 0.294389)
					(end 1.266786 -0.24747)
					(width 0.2)
				)
				(gr_arc
					(start -0.34334 1.279127)
					(mid 0.218448 0.232561)
					(end 1.259603 -0.339191)
					(width 0.2)
				)
				(gr_arc
					(start -0.436309 1.279127)
					(mid 0.152481 0.169693)
					(end 1.255279 -0.431435)
					(width 0.2)
				)
				(gr_arc
					(start -0.529126 1.279127)
					(mid 0.087542 0.105784)
					(end 1.253811 -0.524161)
					(width 0.2)
				)
				(gr_arc
					(start -0.621807 1.279127)
					(mid 0.0309 0.033527)
					(end 1.275473 -0.621136)
					(width 0.2)
				)
				(gr_arc
					(start -0.71437 1.279127)
					(mid -0.037758 -0.026651)
					(end 1.263664 -0.711602)
					(width 0.2)
				)
				(gr_arc
					(start -0.806826 1.279127)
					(mid -0.105837 -0.087395)
					(end 1.253435 -0.802342)
					(width 0.2)
				)
				(gr_arc
					(start -0.899187 1.279127)
					(mid -0.165236 -0.156885)
					(end 1.267475 -0.897258)
					(width 0.2)
				)
				(gr_arc
					(start -0.991463 1.279127)
					(mid -0.228522 -0.222449)
					(end 1.270645 -0.990112)
					(width 0.2)
				)
				(gr_arc
					(start -1.083663 1.279127)
					(mid -0.294507 -0.285313)
					(end 1.266278 -1.081674)
					(width 0.2)
				)
				(gr_line
					(start 1.279127 -0.250195)
					(end 1.279127 -1.083663)
					(width 0.2)
				)
				(gr_line
					(start -0.250195 1.279127)
					(end -1.083663 1.279127)
					(width 0.2)
				)
			)
			(teardrops
				(best_length_ratio 0.2)
				(max_length 1)
				(best_width_ratio 0.9)
				(max_width 2)
				(curved_edges yes)
				(filter_ratio 0.9)
				(enabled yes)
				(allow_two_segments yes)
				(prefer_zone_connections yes)
			)
		)
		(pad "" smd custom
			(at -1.7 1.7 180)
			(size 0.62 0.62)
			(layers "F.Paste")
			(thermal_bridge_angle 90)
			(options
				(clearance outline)
				(anchor circle)
			)
			(primitives
				(gr_arc
					(start -0.250195 1.279127)
					(mid 0.285453 0.294389)
					(end 1.266786 -0.24747)
					(width 0.2)
				)
				(gr_arc
					(start -0.34334 1.279127)
					(mid 0.218448 0.232561)
					(end 1.259603 -0.339191)
					(width 0.2)
				)
				(gr_arc
					(start -0.436309 1.279127)
					(mid 0.152481 0.169693)
					(end 1.255279 -0.431435)
					(width 0.2)
				)
				(gr_arc
					(start -0.529126 1.279127)
					(mid 0.087542 0.105784)
					(end 1.253811 -0.524161)
					(width 0.2)
				)
				(gr_arc
					(start -0.621807 1.279127)
					(mid 0.0309 0.033527)
					(end 1.275473 -0.621136)
					(width 0.2)
				)
				(gr_arc
					(start -0.71437 1.279127)
					(mid -0.037758 -0.026651)
					(end 1.263664 -0.711602)
					(width 0.2)
				)
				(gr_arc
					(start -0.806826 1.279127)
					(mid -0.105837 -0.087395)
					(end 1.253435 -0.802342)
					(width 0.2)
				)
				(gr_arc
					(start -0.899187 1.279127)
					(mid -0.165236 -0.156885)
					(end 1.267475 -0.897258)
					(width 0.2)
				)
				(gr_arc
					(start -0.991463 1.279127)
					(mid -0.228522 -0.222449)
					(end 1.270645 -0.990112)
					(width 0.2)
				)
				(gr_arc
					(start -1.083663 1.279127)
					(mid -0.294507 -0.285313)
					(end 1.266278 -1.081674)
					(width 0.2)
				)
				(gr_line
					(start 1.279127 -0.250195)
					(end 1.279127 -1.083663)
					(width 0.2)
				)
				(gr_line
					(start -0.250195 1.279127)
					(end -1.083663 1.279127)
					(width 0.2)
				)
			)
			(teardrops
				(best_length_ratio 0.2)
				(max_length 1)
				(best_width_ratio 0.9)
				(max_width 2)
				(curved_edges yes)
				(filter_ratio 0.9)
				(enabled yes)
				(allow_two_segments yes)
				(prefer_zone_connections yes)
			)
		)
		(pad "" smd custom
			(at 1.7 -1.7)
			(size 0.62 0.62)
			(layers "F.Paste")
			(thermal_bridge_angle 90)
			(options
				(clearance outline)
				(anchor circle)
			)
			(primitives
				(gr_arc
					(start -0.250195 1.279127)
					(mid 0.285453 0.294389)
					(end 1.266786 -0.24747)
					(width 0.2)
				)
				(gr_arc
					(start -0.34334 1.279127)
					(mid 0.218448 0.232561)
					(end 1.259603 -0.339191)
					(width 0.2)
				)
				(gr_arc
					(start -0.436309 1.279127)
					(mid 0.152481 0.169693)
					(end 1.255279 -0.431435)
					(width 0.2)
				)
				(gr_arc
					(start -0.529126 1.279127)
					(mid 0.087542 0.105784)
					(end 1.253811 -0.524161)
					(width 0.2)
				)
				(gr_arc
					(start -0.621807 1.279127)
					(mid 0.0309 0.033527)
					(end 1.275473 -0.621136)
					(width 0.2)
				)
				(gr_arc
					(start -0.71437 1.279127)
					(mid -0.037758 -0.026651)
					(end 1.263664 -0.711602)
					(width 0.2)
				)
				(gr_arc
					(start -0.806826 1.279127)
					(mid -0.105837 -0.087395)
					(end 1.253435 -0.802342)
					(width 0.2)
				)
				(gr_arc
					(start -0.899187 1.279127)
					(mid -0.165236 -0.156885)
					(end 1.267475 -0.897258)
					(width 0.2)
				)
				(gr_arc
					(start -0.991463 1.279127)
					(mid -0.228522 -0.222449)
					(end 1.270645 -0.990112)
					(width 0.2)
				)
				(gr_arc
					(start -1.083663 1.279127)
					(mid -0.294507 -0.285313)
					(end 1.266278 -1.081674)
					(width 0.2)
				)
				(gr_line
					(start 1.279127 -0.250195)
					(end 1.279127 -1.083663)
					(width 0.2)
				)
				(gr_line
					(start -0.250195 1.279127)
					(end -1.083663 1.279127)
					(width 0.2)
				)
			)
			(teardrops
				(best_length_ratio 0.2)
				(max_length 1)
				(best_width_ratio 0.9)
				(max_width 2)
				(curved_edges yes)
				(filter_ratio 0.9)
				(enabled yes)
				(allow_two_segments yes)
				(prefer_zone_connections yes)
			)
		)
		(pad "" smd custom
			(at 1.7 1.7 270)
			(size 0.62 0.62)
			(layers "F.Paste")
			(thermal_bridge_angle 90)
			(options
				(clearance outline)
				(anchor circle)
			)
			(primitives
				(gr_arc
					(start -0.250195 1.279127)
					(mid 0.285453 0.294389)
					(end 1.266786 -0.24747)
					(width 0.2)
				)
				(gr_arc
					(start -0.34334 1.279127)
					(mid 0.218448 0.232561)
					(end 1.259603 -0.339191)
					(width 0.2)
				)
				(gr_arc
					(start -0.436309 1.279127)
					(mid 0.152481 0.169693)
					(end 1.255279 -0.431435)
					(width 0.2)
				)
				(gr_arc
					(start -0.529126 1.279127)
					(mid 0.087542 0.105784)
					(end 1.253811 -0.524161)
					(width 0.2)
				)
				(gr_arc
					(start -0.621807 1.279127)
					(mid 0.0309 0.033527)
					(end 1.275473 -0.621136)
					(width 0.2)
				)
				(gr_arc
					(start -0.71437 1.279127)
					(mid -0.037758 -0.026651)
					(end 1.263664 -0.711602)
					(width 0.2)
				)
				(gr_arc
					(start -0.806826 1.279127)
					(mid -0.105837 -0.087395)
					(end 1.253435 -0.802342)
					(width 0.2)
				)
				(gr_arc
					(start -0.899187 1.279127)
					(mid -0.165236 -0.156885)
					(end 1.267475 -0.897258)
					(width 0.2)
				)
				(gr_arc
					(start -0.991463 1.279127)
					(mid -0.228522 -0.222449)
					(end 1.270645 -0.990112)
					(width 0.2)
				)
				(gr_arc
					(start -1.083663 1.279127)
					(mid -0.294507 -0.285313)
					(end 1.266278 -1.081674)
					(width 0.2)
				)
				(gr_line
					(start 1.279127 -0.250195)
					(end 1.279127 -1.083663)
					(width 0.2)
				)
				(gr_line
					(start -0.250195 1.279127)
					(end -1.083663 1.279127)
					(width 0.2)
				)
			)
			(teardrops
				(best_length_ratio 0.2)
				(max_length 1)
				(best_width_ratio 0.9)
				(max_width 2)
				(curved_edges yes)
				(filter_ratio 0.9)
				(enabled yes)
				(allow_two_segments yes)
				(prefer_zone_connections yes)
			)
		)
		(pad "1" thru_hole circle
			(at 0 0 90)
			(size 6 6)
			(drill 3.7)
			(layers "*.Cu" "*.Mask")
			(remove_unused_layers no)
			(net 1 "GND")
			(pintype "passive")
			(teardrops
				(best_length_ratio 0.4)
				(max_length 1)
				(best_width_ratio 0.9)
				(max_width 2)
				(curved_edges yes)
				(filter_ratio 0.9)
				(enabled yes)
				(allow_two_segments yes)
				(prefer_zone_connections yes)
			)
		)
	)
	(footprint "antmicro-footprints:R_0402_1005Metric"
		(layer "F.Cu")
		(at 299.05 103.46 -90)
		(descr "Resistor SMD 0402")
		(tags "resistor SMD 0402")
		(property "Reference" "R119"
			(at 0.85 -0.4 90)
			(layer "F.SilkS")
			(effects
				(font
					(size 0.7 0.7)
					(thickness 0.15)
				)
				(justify right bottom)
			)
		)
		(property "Value" "R_0R_0402"
			(at -1.011843 1.772047 90)
			(layer "F.Fab")
			(effects
				(font
					(size 0.7 0.7)
					(thickness 0.15)
				)
				(justify right bottom)
			)
		)
		(property "Datasheet" "https://industrial.panasonic.com/cdbs/www-data/pdf/RDA0000/AOA0000C301.pdf"
			(at 0 0 270)
			(layer "F.Fab")
			(hide yes)
			(effects
				(font
					(size 1.27 1.27)
					(thickness 0.15)
				)
			)
		)
		(property "Author" "Antmicro"
			(at 195.59 402.51 0)
			(layer "F.Fab")
			(hide yes)
			(effects
				(font
					(size 1 1)
					(thickness 0.15)
				)
			)
		)
		(property "Current" "1A"
			(at 195.59 402.51 0)
			(layer "F.Fab")
			(hide yes)
			(effects
				(font
					(size 1 1)
					(thickness 0.15)
				)
			)
		)
		(property "License" "Apache-2.0"
			(at 195.59 402.51 0)
			(layer "F.Fab")
			(hide yes)
			(effects
				(font
					(size 1 1)
					(thickness 0.15)
				)
			)
		)
		(property "MPN" "ERJ2GE0R00X"
			(at 195.59 402.51 0)
			(layer "F.Fab")
			(hide yes)
			(effects
				(font
					(size 1 1)
					(thickness 0.15)
				)
			)
		)
		(property "Manufacturer" "Panasonic"
			(at 195.59 402.51 0)
			(layer "F.Fab")
			(hide yes)
			(effects
				(font
					(size 1 1)
					(thickness 0.15)
				)
			)
		)
		(property "Public" "False"
			(at 195.59 402.51 0)
			(layer "F.Fab")
			(hide yes)
			(effects
				(font
					(size 1 1)
					(thickness 0.15)
				)
			)
		)
		(property "Tolerance" ""
			(at 195.59 402.51 0)
			(layer "F.Fab")
			(hide yes)
			(effects
				(font
					(size 1 1)
					(thickness 0.15)
				)
			)
		)
		(property "Val" "0R"
			(at 195.59 402.51 0)
			(layer "F.Fab")
			(hide yes)
			(effects
				(font
					(size 1 1)
					(thickness 0.15)
				)
			)
		)
		(sheetname "Power")
		(sheetfile "power.kicad_sch")
		(attr smd)
		(fp_rect
			(start -0.925 -0.47)
			(end 0.925 0.47)
			(stroke
				(width 0.05)
				(type default)
			)
			(fill no)
			(layer "F.CrtYd")
		)
		(fp_rect
			(start -0.5 -0.25)
			(end 0.5 0.25)
			(stroke
				(width 0.15)
				(type solid)
			)
			(fill no)
			(layer "F.Fab")
		)
		(pad "1" smd roundrect
			(at -0.48 0 270)
			(size 0.59 0.64)
			(layers "F.Cu" "F.Mask" "F.Paste")
			(roundrect_rratio 0.25)
			(net 79 "Net-(U23-VOUT)")
			(pintype "passive")
			(teardrops
				(best_length_ratio 0.2)
				(max_length 1)
				(best_width_ratio 0.9)
				(max_width 2)
				(curved_edges yes)
				(filter_ratio 0.9)
				(enabled yes)
				(allow_two_segments yes)
				(prefer_zone_connections yes)
			)
		)
		(pad "2" smd roundrect
			(at 0.48 0 270)
			(size 0.59 0.64)
			(layers "F.Cu" "F.Mask" "F.Paste")
			(roundrect_rratio 0.25)
			(net 73 "+3V3_AON")
			(pintype "passive")
			(teardrops
				(best_length_ratio 0.2)
				(max_length 1)
				(best_width_ratio 0.9)
				(max_width 2)
				(curved_edges yes)
				(filter_ratio 0.9)
				(enabled yes)
				(allow_two_segments yes)
				(prefer_zone_connections yes)
			)
		)
	)
	(footprint "antmicro-footprints:LED_0603_1608Metric_G"
		(layer "F.Cu")
		(at 190.70861 74.802163 90)
		(descr "LED SMD 0603 Green")
		(tags "LED SMD 0603 Green")
		(property "Reference" "D30"
			(at -1.1 -0.55 90)
			(layer "F.SilkS")
			(effects
				(font
					(size 0.7 0.7)
					(thickness 0.15)
				)
				(justify left bottom)
			)
		)
		(property "Value" "LED_G_0603_LTST-C190GKT"
			(at -0.001 1.599 90)
			(layer "F.Fab")
			(effects
				(font
					(size 0.7 0.7)
					(thickness 0.15)
				)
				(justify left bottom)
			)
		)
		(property "Datasheet" "https://media.digikey.com/pdf/Data%20Sheets/Lite-On%20PDFs/LTST-C190GKT.pdf"
			(at 0 0 90)
			(layer "F.Fab")
			(hide yes)
			(effects
				(font
					(size 1.27 1.27)
					(thickness 0.15)
				)
			)
		)
		(property "Author" "Antmicro"
			(at 265.510773 -115.906447 0)
			(layer "F.Fab")
			(hide yes)
			(effects
				(font
					(size 1 1)
					(thickness 0.15)
				)
			)
		)
		(property "Color" "Green"
			(at 265.510773 -115.906447 0)
			(layer "F.Fab")
			(hide yes)
			(effects
				(font
					(size 1 1)
					(thickness 0.15)
				)
			)
		)
		(property "License" "Apache-2.0"
			(at 265.510773 -115.906447 0)
			(layer "F.Fab")
			(hide yes)
			(effects
				(font
					(size 1 1)
					(thickness 0.15)
				)
			)
		)
		(property "MPN" "LTST-C190GKT"
			(at 265.510773 -115.906447 0)
			(layer "F.Fab")
			(hide yes)
			(effects
				(font
					(size 1 1)
					(thickness 0.15)
				)
			)
		)
		(property "Manufacturer" "Lite-On"
			(at 265.510773 -115.906447 0)
			(layer "F.Fab")
			(hide yes)
			(effects
				(font
					(size 1 1)
					(thickness 0.15)
				)
			)
		)
		(property "Public" "False"
			(at 265.510773 -115.906447 0)
			(layer "F.Fab")
			(hide yes)
			(effects
				(font
					(size 1 1)
					(thickness 0.15)
				)
			)
		)
		(sheetname "Power")
		(sheetfile "power.kicad_sch")
		(attr smd)
		(fp_line
			(start 0.22 -0.35)
			(end -0.22 -0.35)
			(stroke
				(width 0.15)
				(type solid)
			)
			(layer "F.SilkS")
		)
		(fp_line
			(start -1.18 -0.319)
			(end -1.18 0.321)
			(stroke
				(width 0.15)
				(type solid)
			)
			(layer "F.SilkS")
		)
		(fp_line
			(start 0.105328 0.001008)
			(end 0.24 0.001)
			(stroke
				(width 0.1)
				(type solid)
			)
			(layer "F.SilkS")
		)
		(fp_line
			(start -0.094672 0.001008)
			(end 0.105328 -0.198992)
			(stroke
				(width 0.1)
				(type solid)
			)
			(layer "F.SilkS")
		)
		(fp_line
			(start -0.094672 0.001008)
			(end -0.24 0.001008)
			(stroke
				(width 0.1)
				(type solid)
			)
			(layer "F.SilkS")
		)
		(fp_line
			(start 0.105328 0.201008)
			(end 0.105328 -0.198992)
			(stroke
				(width 0.1)
				(type solid)
			)
			(layer "F.SilkS")
		)
		(fp_line
			(start 0.105328 0.201008)
			(end -0.094672 0.001008)
			(stroke
				(width 0.1)
				(type solid)
			)
			(layer "F.SilkS")
		)
		(fp_line
			(start -0.094672 0.201008)
			(end -0.094672 -0.198992)
			(stroke
				(width 0.1)
				(type solid)
			)
			(layer "F.SilkS")
		)
		(fp_line
			(start 0.22 0.35)
			(end -0.22 0.35)
			(stroke
				(width 0.15)
				(type solid)
			)
			(layer "F.SilkS")
		)
		(fp_rect
			(start 1.25 0.65)
			(end -1.25 -0.65)
			(stroke
				(width 0.05)
				(type solid)
			)
			(fill no)
			(layer "F.CrtYd")
		)
		(fp_line
			(start 0.201 -0.202)
			(end -0.101 0)
			(stroke
				(width 0.15)
				(type solid)
			)
			(layer "F.Fab")
		)
		(fp_line
			(start -0.199 -0.202)
			(end -0.199 0.1)
			(stroke
				(width 0.15)
				(type solid)
			)
			(layer "F.Fab")
		)
		(fp_line
			(start 0.599 0)
			(end 0.201 0)
			(stroke
				(width 0.15)
				(type solid)
			)
			(layer "F.Fab")
		)
		(fp_line
			(start 0.201 0)
			(end 0.201 -0.202)
			(stroke
				(width 0.15)
				(type solid)
			)
			(layer "F.Fab")
		)
		(fp_line
			(start -0.101 0)
			(end 0.201 0.2)
			(stroke
				(width 0.15)
				(type solid)
			)
			(layer "F.Fab")
		)
		(fp_line
			(start -0.199 0)
			(end -0.597 0)
			(stroke
				(width 0.15)
				(type solid)
			)
			(layer "F.Fab")
		)
		(fp_line
			(start 0.201 0.2)
			(end 0.201 0)
			(stroke
				(width 0.15)
				(type solid)
			)
			(layer "F.Fab")
		)
		(fp_line
			(start -0.199 0.2)
			(end -0.199 0.1)
			(stroke
				(width 0.15)
				(type solid)
			)
			(layer "F.Fab")
		)
		(fp_rect
			(start 0.848 0.4)
			(end -0.85 -0.402)
			(stroke
				(width 0.15)
				(type solid)
			)
			(fill no)
			(layer "F.Fab")
		)
		(pad "1" smd roundrect
			(at -0.7 0 270)
			(size 0.8 1)
			(layers "F.Cu" "F.Mask" "F.Paste")
			(roundrect_rratio 0.2)
			(net 982 "Net-(D30-C)")
			(pinfunction "C")
			(pintype "passive")
			(teardrops
				(best_length_ratio 0.2)
				(max_length 1)
				(best_width_ratio 0.9)
				(max_width 2)
				(curved_edges yes)
				(filter_ratio 0.9)
				(enabled yes)
				(allow_two_segments yes)
				(prefer_zone_connections yes)
			)
		)
		(pad "2" smd roundrect
			(at 0.7 0 270)
			(size 0.8 1)
			(layers "F.Cu" "F.Mask" "F.Paste")
			(roundrect_rratio 0.2)
			(net 73 "+3V3_AON")
			(pinfunction "A")
			(pintype "passive")
			(teardrops
				(best_length_ratio 0.2)
				(max_length 1)
				(best_width_ratio 0.9)
				(max_width 2)
				(curved_edges yes)
				(filter_ratio 0.9)
				(enabled yes)
				(allow_two_segments yes)
				(prefer_zone_connections yes)
			)
		)
	)
)
